FILE_TYPE=LIBRARY_PARTS;
primitive 'SCONN21_9193031121LF';
  pin
    '1':
      PIN_NUMBER='(1)';
      BIDIRECTIONAL='TRUE';
      INPUT_LOAD='(-0.01,0.01)';
      OUTPUT_LOAD='(1.0,-1.0)';
    '3':
      PIN_NUMBER='(3)';
      BIDIRECTIONAL='TRUE';
      INPUT_LOAD='(-0.01,0.01)';
      OUTPUT_LOAD='(1.0,-1.0)';
    '4':
      PIN_NUMBER='(4)';
      BIDIRECTIONAL='TRUE';
      INPUT_LOAD='(-0.01,0.01)';
      OUTPUT_LOAD='(1.0,-1.0)';
    '5':
      PIN_NUMBER='(5)';
      BIDIRECTIONAL='TRUE';
      INPUT_LOAD='(-0.01,0.01)';
      OUTPUT_LOAD='(1.0,-1.0)';
    '2':
      PIN_NUMBER='(2)';
      BIDIRECTIONAL='TRUE';
      INPUT_LOAD='(-0.01,0.01)';
      OUTPUT_LOAD='(1.0,-1.0)';
    'G1':
      PIN_NUMBER='(G1)';
      PINUSE='POWER';
      NO_LOAD_CHECK='Both';
      NO_IO_CHECK='Both';
      NO_ASSERT_CHECK='TRUE';
      NO_DIR_CHECK='TRUE';
      ALLOW_CONNECT='TRUE';
    'G2':
      PIN_NUMBER='(G2)';
      PINUSE='POWER';
      NO_LOAD_CHECK='Both';
      NO_IO_CHECK='Both';
      NO_ASSERT_CHECK='TRUE';
      NO_DIR_CHECK='TRUE';
      ALLOW_CONNECT='TRUE';
    '6':
      PIN_NUMBER='(6)';
      BIDIRECTIONAL='TRUE';
      INPUT_LOAD='(-0.01,0.01)';
      OUTPUT_LOAD='(1.0,-1.0)';
    '7':
      PIN_NUMBER='(7)';
      BIDIRECTIONAL='TRUE';
      INPUT_LOAD='(-0.01,0.01)';
      OUTPUT_LOAD='(1.0,-1.0)';
    '8':
      PIN_NUMBER='(8)';
      BIDIRECTIONAL='TRUE';
      INPUT_LOAD='(-0.01,0.01)';
      OUTPUT_LOAD='(1.0,-1.0)';
    '9':
      PIN_NUMBER='(9)';
      BIDIRECTIONAL='TRUE';
      INPUT_LOAD='(-0.01,0.01)';
      OUTPUT_LOAD='(1.0,-1.0)';
    '10':
      PIN_NUMBER='(10)';
      BIDIRECTIONAL='TRUE';
      INPUT_LOAD='(-0.01,0.01)';
      OUTPUT_LOAD='(1.0,-1.0)';
    '11':
      PIN_NUMBER='(11)';
      BIDIRECTIONAL='TRUE';
      INPUT_LOAD='(-0.01,0.01)';
      OUTPUT_LOAD='(1.0,-1.0)';
    '12':
      PIN_NUMBER='(12)';
      BIDIRECTIONAL='TRUE';
      INPUT_LOAD='(-0.01,0.01)';
      OUTPUT_LOAD='(1.0,-1.0)';
    '13':
      PIN_NUMBER='(13)';
      BIDIRECTIONAL='TRUE';
      INPUT_LOAD='(-0.01,0.01)';
      OUTPUT_LOAD='(1.0,-1.0)';
    '14':
      PIN_NUMBER='(14)';
      BIDIRECTIONAL='TRUE';
      INPUT_LOAD='(-0.01,0.01)';
      OUTPUT_LOAD='(1.0,-1.0)';
    '15':
      PIN_NUMBER='(15)';
      BIDIRECTIONAL='TRUE';
      INPUT_LOAD='(-0.01,0.01)';
      OUTPUT_LOAD='(1.0,-1.0)';
    '16':
      PIN_NUMBER='(16)';
      BIDIRECTIONAL='TRUE';
      INPUT_LOAD='(-0.01,0.01)';
      OUTPUT_LOAD='(1.0,-1.0)';
    '17':
      PIN_NUMBER='(17)';
      BIDIRECTIONAL='TRUE';
      INPUT_LOAD='(-0.01,0.01)';
      OUTPUT_LOAD='(1.0,-1.0)';
    '18':
      PIN_NUMBER='(18)';
      BIDIRECTIONAL='TRUE';
      INPUT_LOAD='(-0.01,0.01)';
      OUTPUT_LOAD='(1.0,-1.0)';
    '19':
      PIN_NUMBER='(19)';
      BIDIRECTIONAL='TRUE';
      INPUT_LOAD='(-0.01,0.01)';
      OUTPUT_LOAD='(1.0,-1.0)';
    '20':
      PIN_NUMBER='(20)';
      BIDIRECTIONAL='TRUE';
      INPUT_LOAD='(-0.01,0.01)';
      OUTPUT_LOAD='(1.0,-1.0)';
    '21':
      PIN_NUMBER='(21)';
      BIDIRECTIONAL='TRUE';
      INPUT_LOAD='(-0.01,0.01)';
      OUTPUT_LOAD='(1.0,-1.0)';
  end_pin;
  body
    PART_NAME='SCONN21_9193031121LF';
    BODY_NAME='SCONN21_9193031121LF';
    PHYS_DES_PREFIX='J';
    CLASS='IO';
    NC_PINS='(H1,H2)';
  end_body;
end_primitive;

END.
